# T6G (Grand Teton) — schematic netlist excerpt (pin names and nets, part order shuffled) for the footprints in the layout excerpt that follows; sources: Cadence DE-HDL packaged netlist, KiCad conversion of 04192023_DAF0TMB3IC0_F0TG_MB_C_brd_V02_OCP.brd

PR130  Q_RES  1 1% CHIP  pkg 0402LF  page 207 : A = PVDD11_S3_P0_VCC ; B = P3V3_AUX
R6314  Q_RES  0 5% CHIP  pkg 0402LF  page 178 : A = SMB_USB_CPU0_HUB1_SCL ; B = USB_HUB2_TI_OVERCUR2_MRP_PROG_FUNC5

(kicad_pcb
	(version 20260206)
	(generator "pcbnew")
	(generator_version "10.0")
	(general
		(thickness 1.6)
		(legacy_teardrops no)
	)
	(paper "A4")
	(title_block
		(title "04192023_DAF0TMB3IC0_F0TG_MB_C_brd_V02_OCP.brd")
		(comment 1 "Grand Teton / footprints 2348-2349 of 8354")
	)
	(layers
		(0 "F.Cu" signal "TOP")
		(4 "In1.Cu" signal "GND")
		(6 "In2.Cu" signal "IN1")
		(8 "In3.Cu" signal "GND1")
		(10 "In4.Cu" signal "IN2")
		(12 "In5.Cu" signal "GND2")
		(14 "In6.Cu" signal "IN3")
		(16 "In7.Cu" signal "GND3")
		(18 "In8.Cu" signal "VCC")
		(20 "In9.Cu" signal "VCC1")
		(22 "In10.Cu" signal "GND4")
		(24 "In11.Cu" signal "IN4")
		(26 "In12.Cu" signal "GND5")
		(28 "In13.Cu" signal "IN5")
		(30 "In14.Cu" signal "GND6")
		(32 "In15.Cu" signal "IN6")
		(34 "In16.Cu" signal "GND7")
		(2 "B.Cu" signal "BOTTOM")
		(9 "F.Adhes" user "F.Adhesive")
		(11 "B.Adhes" user "B.Adhesive")
		(13 "F.Paste" user "Package Geometry/Pastemask Top")
		(15 "B.Paste" user "Package Geometry/Pastemask Bottom")
		(5 "F.SilkS" user "Ref Des/Silkscreen Top")
		(7 "B.SilkS" user "Ref Des/Silkscreen Bottom")
		(1 "F.Mask" user "Board Geometry/Soldermask Top")
		(3 "B.Mask" user "Board Geometry/Soldermask Bottom")
		(17 "Dwgs.User" user "User.Drawings")
		(19 "Cmts.User" user "User.Comments")
		(21 "Eco1.User" user "User.Eco1")
		(23 "Eco2.User" user "User.Eco2")
		(25 "Edge.Cuts" user "Board Geometry/Outline")
		(27 "Margin" user)
		(31 "F.CrtYd" user "Package Geometry/Place Bound Top")
		(29 "B.CrtYd" user "Package Geometry/Place Bound Bottom")
		(35 "F.Fab" user "Ref Des/Assembly Top")
		(33 "B.Fab" user "Ref Des/Assembly Bottom")
	)
	(footprint ""
		(layer "F.Cu")
		(at 424.217338 -365.797846 90)
		(property "Reference" "PR130"
			(at 0 0 90)
			(layer "F.SilkS")
			(hide yes)
			(effects
				(font
					(size 1.27 1.27)
				)
			)
		)
		(property "Value" ""
			(at 0 0 90)
			(layer "F.Fab")
			(effects
				(font
					(size 1.27 1.27)
				)
			)
		)
		(duplicate_pad_numbers_are_jumpers no)
		(fp_line
			(start 0.7874 -0.4064)
			(end 0.7874 0.4064)
			(stroke
				(width 0.1524)
				(type default)
			)
			(layer "F.SilkS")
		)
		(fp_line
			(start -0.7874 -0.4064)
			(end 0.7874 -0.4064)
			(stroke
				(width 0.1524)
				(type default)
			)
			(layer "F.SilkS")
		)
		(fp_line
			(start 0.7874 0.4064)
			(end -0.7874 0.4064)
			(stroke
				(width 0.1524)
				(type default)
			)
			(layer "F.SilkS")
		)
		(fp_line
			(start -0.7874 0.4064)
			(end -0.7874 -0.4064)
			(stroke
				(width 0.1524)
				(type default)
			)
			(layer "F.SilkS")
		)
		(fp_line
			(start -0.12065 -0.305054)
			(end -0.12065 -0.2794)
			(stroke
				(width 0.1)
				(type default)
			)
			(layer "F.Fab")
		)
		(fp_line
			(start -0.67945 -0.305054)
			(end -0.12065 -0.305054)
			(stroke
				(width 0.1)
				(type default)
			)
			(layer "F.Fab")
		)
		(fp_line
			(start 0.67945 -0.3048)
			(end 0.67945 0.3048)
			(stroke
				(width 0.1)
				(type default)
			)
			(layer "F.Fab")
		)
		(fp_line
			(start 0.12065 -0.3048)
			(end 0.67945 -0.3048)
			(stroke
				(width 0.1)
				(type default)
			)
			(layer "F.Fab")
		)
		(fp_line
			(start 0.12065 -0.2794)
			(end 0.12065 -0.3048)
			(stroke
				(width 0.1)
				(type default)
			)
			(layer "F.Fab")
		)
		(fp_line
			(start -0.12065 -0.2794)
			(end 0.12065 -0.2794)
			(stroke
				(width 0.1)
				(type default)
			)
			(layer "F.Fab")
		)
		(fp_line
			(start 0.120396 0.2794)
			(end -0.12065 0.2794)
			(stroke
				(width 0.1)
				(type default)
			)
			(layer "F.Fab")
		)
		(fp_line
			(start -0.12065 0.2794)
			(end -0.12065 0.3048)
			(stroke
				(width 0.1)
				(type default)
			)
			(layer "F.Fab")
		)
		(fp_line
			(start 0.67945 0.3048)
			(end 0.120396 0.3048)
			(stroke
				(width 0.1)
				(type default)
			)
			(layer "F.Fab")
		)
		(fp_line
			(start 0.120396 0.3048)
			(end 0.120396 0.2794)
			(stroke
				(width 0.1)
				(type default)
			)
			(layer "F.Fab")
		)
		(fp_line
			(start -0.12065 0.3048)
			(end -0.67945 0.3048)
			(stroke
				(width 0.1)
				(type default)
			)
			(layer "F.Fab")
		)
		(fp_line
			(start -0.67945 0.3048)
			(end -0.67945 -0.305054)
			(stroke
				(width 0.1)
				(type default)
			)
			(layer "F.Fab")
		)
		(pad "1" smd circle
			(at -0.40005 0 90)
			(size 0 0)
			(layers "F.Cu" "F.Mask" "F.Paste")
			(net "PVDD11_S3_P0_VCC")
		)
		(pad "2" smd circle
			(at 0.40005 0 90)
			(size 0 0)
			(layers "F.Cu" "F.Mask" "F.Paste")
			(net "P3V3_AUX")
		)
	)
	(footprint ""
		(layer "F.Cu")
		(at 106.501946 -52.86248 -90)
		(property "Reference" "R6314"
			(at 0 0 270)
			(layer "F.SilkS")
			(hide yes)
			(effects
				(font
					(size 1.27 1.27)
				)
			)
		)
		(property "Value" ""
			(at 0 0 270)
			(layer "F.Fab")
			(effects
				(font
					(size 1.27 1.27)
				)
			)
		)
		(duplicate_pad_numbers_are_jumpers no)
		(fp_line
			(start -0.7874 0.4064)
			(end -0.7874 -0.4064)
			(stroke
				(width 0.1524)
				(type default)
			)
			(layer "F.SilkS")
		)
		(fp_line
			(start 0.7874 0.4064)
			(end -0.7874 0.4064)
			(stroke
				(width 0.1524)
				(type default)
			)
			(layer "F.SilkS")
		)
		(fp_line
			(start -0.7874 -0.4064)
			(end 0.7874 -0.4064)
			(stroke
				(width 0.1524)
				(type default)
			)
			(layer "F.SilkS")
		)
		(fp_line
			(start 0.7874 -0.4064)
			(end 0.7874 0.4064)
			(stroke
				(width 0.1524)
				(type default)
			)
			(layer "F.SilkS")
		)
		(fp_line
			(start -0.67945 0.3048)
			(end -0.67945 -0.305054)
			(stroke
				(width 0.1)
				(type default)
			)
			(layer "F.Fab")
		)
		(fp_line
			(start -0.12065 0.3048)
			(end -0.67945 0.3048)
			(stroke
				(width 0.1)
				(type default)
			)
			(layer "F.Fab")
		)
		(fp_line
			(start 0.120396 0.3048)
			(end 0.120396 0.2794)
			(stroke
				(width 0.1)
				(type default)
			)
			(layer "F.Fab")
		)
		(fp_line
			(start 0.67945 0.3048)
			(end 0.120396 0.3048)
			(stroke
				(width 0.1)
				(type default)
			)
			(layer "F.Fab")
		)
		(fp_line
			(start -0.12065 0.2794)
			(end -0.12065 0.3048)
			(stroke
				(width 0.1)
				(type default)
			)
			(layer "F.Fab")
		)
		(fp_line
			(start 0.120396 0.2794)
			(end -0.12065 0.2794)
			(stroke
				(width 0.1)
				(type default)
			)
			(layer "F.Fab")
		)
		(fp_line
			(start -0.12065 -0.2794)
			(end 0.12065 -0.2794)
			(stroke
				(width 0.1)
				(type default)
			)
			(layer "F.Fab")
		)
		(fp_line
			(start 0.12065 -0.2794)
			(end 0.12065 -0.3048)
			(stroke
				(width 0.1)
				(type default)
			)
			(layer "F.Fab")
		)
		(fp_line
			(start 0.12065 -0.3048)
			(end 0.67945 -0.3048)
			(stroke
				(width 0.1)
				(type default)
			)
			(layer "F.Fab")
		)
		(fp_line
			(start 0.67945 -0.3048)
			(end 0.67945 0.3048)
			(stroke
				(width 0.1)
				(type default)
			)
			(layer "F.Fab")
		)
		(fp_line
			(start -0.67945 -0.305054)
			(end -0.12065 -0.305054)
			(stroke
				(width 0.1)
				(type default)
			)
			(layer "F.Fab")
		)
		(fp_line
			(start -0.12065 -0.305054)
			(end -0.12065 -0.2794)
			(stroke
				(width 0.1)
				(type default)
			)
			(layer "F.Fab")
		)
		(pad "1" smd circle
			(at -0.40005 0 270)
			(size 0 0)
			(layers "F.Cu" "F.Mask" "F.Paste")
			(net "SMB_USB_CPU0_HUB1_SCL")
		)
		(pad "2" smd circle
			(at 0.40005 0 270)
			(size 0 0)
			(layers "F.Cu" "F.Mask" "F.Paste")
			(net "USB_HUB2_TI_OVERCUR2_MRP_PROG_FUNC5")
		)
	)
)
